# BASEBOARD_FAB2 (Tioga Pass) — schematic netlist excerpt (pin names and nets, part order shuffled) for the footprints in the layout excerpt that follows; sources: Cadence DE-HDL packaged netlist, KiCad conversion of Wiwynn_Tioga_Pass_MB.brd

C1G6  CAP  1.0UF 16V 10% X6S  pkg 0402  page 224 : A = VR_PVDDQ_GHJ_PH1_VCIN ; B = GND

Q7E7  MOSFET_N  BSZ019N03LS NFET  pkg LCC3  page 198
  SRC  = P12V
  GATE  = P12V_SWITCH_G
  DRN  = P12V_STBY

R8E6  RES  1.00K 1% EMPTY  pkg 0402  page 125 : A = P3V3_STBY ; B = SPI_PCH_MOSI

(kicad_pcb
	(version 20260206)
	(generator "pcbnew")
	(generator_version "10.0")
	(general
		(thickness 1.6)
		(legacy_teardrops no)
	)
	(paper "A4")
	(title_block
		(title "Wiwynn_Tioga_Pass_MB.brd")
		(comment 1 "Tioga Pass / footprints 1642-1644 of 4770")
	)
	(layers
		(0 "F.Cu" signal "TOP")
		(4 "In1.Cu" signal "L2GND")
		(6 "In2.Cu" signal "L3")
		(8 "In3.Cu" signal "L4GND")
		(10 "In4.Cu" signal "L5")
		(12 "In5.Cu" signal "L6GND")
		(14 "In6.Cu" signal "L7VCC")
		(16 "In7.Cu" signal "L8VCC")
		(18 "In8.Cu" signal "L9GND")
		(20 "In9.Cu" signal "L10")
		(22 "In10.Cu" signal "L11GND")
		(24 "In11.Cu" signal "L12")
		(26 "In12.Cu" signal "L13GND")
		(2 "B.Cu" signal "BOTTOM")
		(9 "F.Adhes" user "F.Adhesive")
		(11 "B.Adhes" user "B.Adhesive")
		(13 "F.Paste" user "Package Geometry/Pastemask Top")
		(15 "B.Paste" user "Package Geometry/Pastemask Bottom")
		(5 "F.SilkS" user "Ref Des/Silkscreen Top")
		(7 "B.SilkS" user "Ref Des/Silkscreen Bottom")
		(1 "F.Mask" user "Board Geometry/Soldermask Top")
		(3 "B.Mask" user "Board Geometry/Soldermask Bottom")
		(17 "Dwgs.User" user "User.Drawings")
		(19 "Cmts.User" user "User.Comments")
		(21 "Eco1.User" user "User.Eco1")
		(23 "Eco2.User" user "User.Eco2")
		(25 "Edge.Cuts" user "Board Geometry/Outline")
		(27 "Margin" user)
		(31 "F.CrtYd" user "Package Geometry/Place Bound Top")
		(29 "B.CrtYd" user "Package Geometry/Place Bound Bottom")
		(35 "F.Fab" user "Ref Des/Assembly Top")
		(33 "B.Fab" user "Ref Des/Assembly Bottom")
	)
	(footprint ""
		(layer "F.Cu")
		(at 492.315246 -20.549108 90)
		(property "Reference" "Q7E7"
			(at 4.16433 -1.143 0)
			(unlocked yes)
			(layer "F.SilkS")
			(effects
				(font
					(size 0.7874 0.5842)
					(thickness 0.1524)
				)
				(justify left)
			)
		)
		(property "Value" ""
			(at 0 0 90)
			(layer "F.Fab")
			(effects
				(font
					(size 1.27 1.27)
				)
			)
		)
		(duplicate_pad_numbers_are_jumpers no)
		(fp_line
			(start -0.245364 -1.379982)
			(end 3.15468 -1.379982)
			(stroke
				(width 0.1524)
				(type default)
			)
			(layer "F.SilkS")
		)
		(fp_line
			(start -0.245364 2.020062)
			(end 3.15468 2.020062)
			(stroke
				(width 0.1524)
				(type default)
			)
			(layer "F.SilkS")
		)
		(fp_circle
			(center -0.94996 -1.512316)
			(end -0.94996 -1.385316)
			(stroke
				(width 0.254)
				(type default)
			)
			(fill no)
			(layer "F.SilkS")
		)
		(fp_poly
			(pts
				(xy 0.890016 -0.82296) (xy 0.890016 1.46304) (xy 3.404616 1.46304) (xy 3.404616 1.13284) (xy 2.617216 1.13284)
				(xy 2.617216 0.811022) (xy 3.404616 0.811022) (xy 3.404616 0.480822) (xy 2.617216 0.480822) (xy 2.617216 0.159258)
				(xy 3.404616 0.159258) (xy 3.404616 -0.170942) (xy 2.617216 -0.170942) (xy 2.617216 -0.49276) (xy 3.404616 -0.49276)
				(xy 3.404616 -0.82296)
			)
			(stroke
				(width 0)
				(type default)
			)
			(fill yes)
			(layer "F.Paste")
		)
		(fp_poly
			(pts
				(xy -0.245364 -1.379982) (xy -0.245364 2.020062) (xy 3.15468 2.020062) (xy 3.15468 -1.379982)
			)
			(stroke
				(width 0)
				(type default)
			)
			(fill no)
			(layer "F.CrtYd")
		)
		(fp_line
			(start 3.15468 -1.379982)
			(end 3.15468 2.020062)
			(stroke
				(width 0.1)
				(type default)
			)
			(layer "F.Fab")
		)
		(fp_line
			(start -0.245364 -1.379982)
			(end 3.15468 -1.379982)
			(stroke
				(width 0.1)
				(type default)
			)
			(layer "F.Fab")
		)
		(fp_line
			(start 3.15468 2.020062)
			(end -0.245364 2.020062)
			(stroke
				(width 0.1)
				(type default)
			)
			(layer "F.Fab")
		)
		(fp_line
			(start -0.245364 2.020062)
			(end -0.245364 -1.379982)
			(stroke
				(width 0.1)
				(type default)
			)
			(layer "F.Fab")
		)
		(fp_circle
			(center -0.94996 -1.512316)
			(end -0.94996 -1.385316)
			(stroke
				(width 0.254)
				(type default)
			)
			(fill no)
			(layer "F.Fab")
		)
		(pad "1" smd custom
			(at 0 0 90)
			(size 0.24765 0.24765)
			(layers "F.Cu" "F.Mask" "F.Paste")
			(net "P12V")
			(options
				(clearance outline)
				(anchor circle)
			)
			(primitives
				(gr_poly
					(pts
						(xy 0.4953 0.8255) (xy 0.4953 -0.8255) (xy -0.4953 -0.8255) (xy -0.4953 -0.4953) (xy 0.0127 -0.4953)
						(xy 0.0127 -0.1651) (xy -0.4953 -0.1651) (xy -0.4953 0.1651) (xy 0.0127 0.1651) (xy 0.0127 0.4953)
						(xy -0.4953 0.4953) (xy -0.4953 0.8255)
					)
					(width 0)
					(fill yes)
				)
			)
		)
		(pad "4" smd rect
			(at 0 1.30048 90)
			(size 0.9906 0.3302)
			(layers "F.Cu" "F.Mask" "F.Paste")
			(net "P12V_SWITCH_G")
		)
		(pad "5" smd custom
			(at 2.147316 0.32004 90)
			(size 0.5715 0.5715)
			(layers "F.Cu" "F.Mask" "F.Paste")
			(net "P12V_STBY")
			(options
				(clearance outline)
				(anchor circle)
			)
			(primitives
				(gr_poly
					(pts
						(xy -1.2573 -1.143) (xy -1.2573 1.143) (xy 1.2573 1.143) (xy 1.2573 0.8128) (xy 0.4699 0.8128)
						(xy 0.4699 0.490982) (xy 1.2573 0.490982) (xy 1.2573 0.160782) (xy 0.4699 0.160782) (xy 0.4699 -0.160782)
						(xy 1.2573 -0.160782) (xy 1.2573 -0.490982) (xy 0.4699 -0.490982) (xy 0.4699 -0.8128) (xy 1.2573 -0.8128)
						(xy 1.2573 -1.143)
					)
					(width 0)
					(fill yes)
				)
			)
		)
	)
	(footprint ""
		(layer "F.Cu")
		(at 407.8351 -63.373 -90)
		(property "Reference" "R8E6"
			(at 0 0 270)
			(layer "F.SilkS")
			(hide yes)
			(effects
				(font
					(size 1.27 1.27)
				)
			)
		)
		(property "Value" ""
			(at 0 0 270)
			(layer "F.Fab")
			(effects
				(font
					(size 1.27 1.27)
				)
			)
		)
		(duplicate_pad_numbers_are_jumpers no)
		(fp_poly
			(pts
				(xy -0.2794 -0.1016) (xy 0.2794 -0.1016) (xy 0.2794 0.9906) (xy -0.2794 0.9906)
			)
			(stroke
				(width 0)
				(type default)
			)
			(fill no)
			(layer "F.CrtYd")
		)
		(pad "1" smd rect
			(at 0 0 270)
			(size 0.508 0.508)
			(layers "F.Cu" "F.Mask" "F.Paste")
			(net "P3V3_STBY")
		)
		(pad "2" smd rect
			(at 0 0.889 270)
			(size 0.508 0.508)
			(layers "F.Cu" "F.Mask" "F.Paste")
			(net "SPI_PCH_MOSI")
		)
		(zone
			(layer "F.Cu")
			(hatch none 0.5)
			(connect_pads
				(clearance 0)
			)
			(min_thickness 0.25)
			(keepout
				(tracks not_allowed)
				(vias allowed)
				(pads allowed)
				(copperpour not_allowed)
				(footprints allowed)
			)
			(placement
				(enabled no)
				(sheetname "")
			)
			(fill
				(thermal_gap 0.5)
				(thermal_bridge_width 0.5)
				(island_removal_mode 0)
			)
			(polygon
				(pts
					(xy 407.2001 -63.627) (xy 407.2001 -63.119) (xy 407.5811 -63.119) (xy 407.5811 -63.627)
				)
			)
		)
		(zone
			(layer "F.Cu")
			(hatch none 0.5)
			(connect_pads
				(clearance 0)
			)
			(min_thickness 0.25)
			(keepout
				(tracks allowed)
				(vias not_allowed)
				(pads allowed)
				(copperpour not_allowed)
				(footprints allowed)
			)
			(placement
				(enabled no)
				(sheetname "")
			)
			(fill
				(thermal_gap 0.5)
				(thermal_bridge_width 0.5)
				(island_removal_mode 0)
			)
			(polygon
				(pts
					(xy 407.5811 -63.627) (xy 407.5811 -63.119) (xy 407.2001 -63.119) (xy 407.2001 -63.627)
				)
			)
		)
	)
	(footprint ""
		(layer "F.Cu")
		(at 3.2004 -5.675376 -90)
		(property "Reference" "C1G6"
			(at 0 0 270)
			(layer "F.SilkS")
			(hide yes)
			(effects
				(font
					(size 1.27 1.27)
				)
			)
		)
		(property "Value" ""
			(at 0 0 270)
			(layer "F.Fab")
			(effects
				(font
					(size 1.27 1.27)
				)
			)
		)
		(duplicate_pad_numbers_are_jumpers no)
		(fp_poly
			(pts
				(xy 0.3048 -0.1016) (xy 0.3048 0.9906) (xy -0.3048 0.9906) (xy -0.3048 -0.1016)
			)
			(stroke
				(width 0)
				(type default)
			)
			(fill no)
			(layer "F.CrtYd")
		)
		(fp_line
			(start -0.3048 0.9906)
			(end 0.3048 0.9906)
			(stroke
				(width 0.1)
				(type default)
			)
			(layer "F.Fab")
		)
		(fp_line
			(start 0.3048 0.9906)
			(end 0.3048 -0.1016)
			(stroke
				(width 0.1)
				(type default)
			)
			(layer "F.Fab")
		)
		(fp_line
			(start -0.3048 -0.1016)
			(end -0.3048 0.9906)
			(stroke
				(width 0.1)
				(type default)
			)
			(layer "F.Fab")
		)
		(fp_line
			(start 0.3048 -0.1016)
			(end -0.3048 -0.1016)
			(stroke
				(width 0.1)
				(type default)
			)
			(layer "F.Fab")
		)
		(pad "1" smd rect
			(at 0 0 270)
			(size 0.508 0.508)
			(layers "F.Cu" "F.Mask" "F.Paste")
			(net "VR_PVDDQ_GHJ_PH1_VCIN")
		)
		(pad "2" smd rect
			(at 0 0.889 270)
			(size 0.508 0.508)
			(layers "F.Cu" "F.Mask" "F.Paste")
			(net "GND")
		)
		(zone
			(layer "F.Cu")
			(hatch none 0.5)
			(connect_pads
				(clearance 0)
			)
			(min_thickness 0.25)
			(keepout
				(tracks not_allowed)
				(vias allowed)
				(pads allowed)
				(copperpour not_allowed)
				(footprints allowed)
			)
			(placement
				(enabled no)
				(sheetname "")
			)
			(fill
				(thermal_gap 0.5)
				(thermal_bridge_width 0.5)
				(island_removal_mode 0)
			)
			(polygon
				(pts
					(xy 2.5654 -5.929376) (xy 2.5654 -5.421376) (xy 2.9464 -5.421376) (xy 2.9464 -5.929376)
				)
			)
		)
		(zone
			(layer "F.Cu")
			(hatch none 0.5)
			(connect_pads
				(clearance 0)
			)
			(min_thickness 0.25)
			(keepout
				(tracks allowed)
				(vias not_allowed)
				(pads allowed)
				(copperpour not_allowed)
				(footprints allowed)
			)
			(placement
				(enabled no)
				(sheetname "")
			)
			(fill
				(thermal_gap 0.5)
				(thermal_bridge_width 0.5)
				(island_removal_mode 0)
			)
			(polygon
				(pts
					(xy 2.9464 -5.929376) (xy 2.9464 -5.421376) (xy 2.5654 -5.421376) (xy 2.5654 -5.929376)
				)
			)
		)
	)
)
